(kicad_pcb
	(version 20260206)
	(generator "pcbnew")
	(generator_version "10.0")
	(general
		(thickness 1.6)
		(legacy_teardrops no)
	)
	(paper "A4")
	(title_block
		(title "dpb — 14545-sa.0730WZS0815.brd")
		(comment 1 "Honey Badger (Wiwynn) / footprints 434-437 of 1066")
	)
	(layers
		(0 "F.Cu" signal "TOP")
		(4 "In1.Cu" signal "L2GND")
		(6 "In2.Cu" signal "L3")
		(8 "In3.Cu" signal "L4VCC")
		(10 "In4.Cu" signal "L5VCC")
		(12 "In5.Cu" signal "L6")
		(14 "In6.Cu" signal "L7GND")
		(2 "B.Cu" signal "BOTTOM")
		(9 "F.Adhes" user "F.Adhesive")
		(11 "B.Adhes" user "B.Adhesive")
		(13 "F.Paste" user "Package Geometry/Pastemask Top")
		(15 "B.Paste" user "Package Geometry/Pastemask Bottom")
		(5 "F.SilkS" user "Ref Des/Silkscreen Top")
		(7 "B.SilkS" user "Ref Des/Silkscreen Bottom")
		(1 "F.Mask" user "Board Geometry/Soldermask Top")
		(3 "B.Mask" user "Board Geometry/Soldermask Bottom")
		(17 "Dwgs.User" user "User.Drawings")
		(19 "Cmts.User" user "User.Comments")
		(21 "Eco1.User" user "User.Eco1")
		(23 "Eco2.User" user "User.Eco2")
		(25 "Edge.Cuts" user "Board Geometry/Outline")
		(27 "Margin" user)
		(31 "F.CrtYd" user "Package Geometry/Place Bound Top")
		(29 "B.CrtYd" user "Package Geometry/Place Bound Bottom")
		(35 "F.Fab" user "Ref Des/Assembly Top")
		(33 "B.Fab" user "Ref Des/Assembly Bottom")
	)
	(footprint ""
		(layer "F.Cu")
		(at 162.572446 -455.837036)
		(property "Reference" "R482"
			(at 0 0 0)
			(layer "F.SilkS")
			(hide yes)
			(effects
				(font
					(size 1.27 1.27)
				)
			)
		)
		(property "Value" "10KR2F-2-GP"
			(at 0.064008 -3.993896 0)
			(unlocked yes)
			(layer "F.Fab")
			(hide yes)
			(effects
				(font
					(size 1.016 1.016)
					(thickness 0.1524)
				)
			)
		)
		(property "Device Type" "R402H16"
			(at 0.064008 -5.517896 0)
			(unlocked yes)
			(layer "F.Fab")
			(hide yes)
			(effects
				(font
					(size 1.016 1.016)
					(thickness 0.1524)
				)
			)
		)
		(duplicate_pad_numbers_are_jumpers no)
		(fp_line
			(start -0.508 -0.9398)
			(end -0.508 0.9398)
			(stroke
				(width 0.1524)
				(type default)
			)
			(layer "F.SilkS")
		)
		(fp_line
			(start 0.508 -0.9398)
			(end -0.508 -0.9398)
			(stroke
				(width 0.1524)
				(type default)
			)
			(layer "F.SilkS")
		)
		(fp_rect
			(start -0.508 0.9398)
			(end 0.508 -0.9398)
			(stroke
				(width 0)
				(type default)
			)
			(fill no)
			(layer "F.CrtYd")
		)
		(fp_rect
			(start -0.508 0.9398)
			(end 0.508 -0.9398)
			(stroke
				(width 0)
				(type default)
			)
			(fill no)
			(layer "F.Fab")
		)
		(pad "1" smd custom
			(at 0 -0.4445)
			(size 0.1397 0.1397)
			(layers "F.Cu" "F.Mask" "F.Paste")
			(net "P5VB_DIV")
			(options
				(clearance outline)
				(anchor circle)
			)
			(primitives
				(gr_poly
					(pts
						(arc
							(start -0.1778 -0.2794)
							(mid -0.249642 -0.249642)
							(end -0.2794 -0.1778)
						)
						(arc
							(start -0.2794 0.1778)
							(mid -0.249642 0.249642)
							(end -0.1778 0.2794)
						)
						(arc
							(start 0.1778 0.2794)
							(mid 0.249642 0.249642)
							(end 0.2794 0.1778)
						)
						(arc
							(start 0.2794 -0.1778)
							(mid 0.249642 -0.249642)
							(end 0.1778 -0.2794)
						)
					)
					(width 0)
					(fill yes)
				)
			)
		)
		(pad "2" smd custom
			(at 0 0.4445)
			(size 0.1397 0.1397)
			(layers "F.Cu" "F.Mask" "F.Paste")
			(net "GND")
			(options
				(clearance outline)
				(anchor circle)
			)
			(primitives
				(gr_poly
					(pts
						(arc
							(start -0.1778 -0.2794)
							(mid -0.249642 -0.249642)
							(end -0.2794 -0.1778)
						)
						(arc
							(start -0.2794 0.1778)
							(mid -0.249642 0.249642)
							(end -0.1778 0.2794)
						)
						(arc
							(start 0.1778 0.2794)
							(mid 0.249642 0.249642)
							(end 0.2794 0.1778)
						)
						(arc
							(start 0.2794 -0.1778)
							(mid 0.249642 -0.249642)
							(end 0.1778 -0.2794)
						)
					)
					(width 0)
					(fill yes)
				)
			)
		)
	)
	(footprint ""
		(layer "F.Cu")
		(at 43.179746 -209.197702 180)
		(property "Reference" "U39"
			(at 0 0 180)
			(layer "F.SilkS")
			(hide yes)
			(effects
				(font
					(size 1.27 1.27)
				)
			)
		)
		(property "Value" "74LVC1G08GW-1-GP"
			(at -2.3368 -8.6868 180)
			(unlocked yes)
			(layer "F.Fab")
			(hide yes)
			(effects
				(font
					(size 1.016 1.016)
					(thickness 0.1524)
				)
			)
		)
		(property "Device Type" "SC70-5H44"
			(at -2.3114 -10.414 180)
			(unlocked yes)
			(layer "F.Fab")
			(hide yes)
			(effects
				(font
					(size 1.016 1.016)
					(thickness 0.1524)
				)
			)
		)
		(duplicate_pad_numbers_are_jumpers no)
		(fp_line
			(start 1.3843 -1.8034)
			(end 1.3843 -1.1176)
			(stroke
				(width 0.3302)
				(type default)
			)
			(layer "F.SilkS")
		)
		(fp_line
			(start 1.27 1.7018)
			(end -1.27 1.7018)
			(stroke
				(width 0.1524)
				(type default)
			)
			(layer "F.SilkS")
		)
		(fp_line
			(start 1.27 -1.7018)
			(end 1.27 1.7018)
			(stroke
				(width 0.1524)
				(type default)
			)
			(layer "F.SilkS")
		)
		(fp_line
			(start 0.6604 -1.8034)
			(end 1.3843 -1.8034)
			(stroke
				(width 0.3302)
				(type default)
			)
			(layer "F.SilkS")
		)
		(fp_line
			(start -1.27 1.7018)
			(end -1.27 -1.7018)
			(stroke
				(width 0.1524)
				(type default)
			)
			(layer "F.SilkS")
		)
		(fp_line
			(start -1.27 -1.7018)
			(end 1.27 -1.7018)
			(stroke
				(width 0.1524)
				(type default)
			)
			(layer "F.SilkS")
		)
		(fp_rect
			(start -1.524 1.9558)
			(end 1.524 -1.9558)
			(stroke
				(width 0)
				(type default)
			)
			(fill no)
			(layer "F.CrtYd")
		)
		(fp_poly
			(pts
				(xy -1.524 -1.9558) (xy 1.524 -1.9558) (xy 1.524 1.9558) (xy -1.524 1.9558)
			)
			(stroke
				(width 0)
				(type default)
			)
			(fill no)
			(layer "F.Fab")
		)
		(pad "1" smd rect
			(at 0.65024 -0.8255 180)
			(size 0.4064 1.2192)
			(layers "F.Cu" "F.Mask" "F.Paste")
			(net "SAS_EXP_B_PWR12")
		)
		(pad "2" smd rect
			(at 0 -0.8255 180)
			(size 0.4064 1.2192)
			(layers "F.Cu" "F.Mask" "F.Paste")
			(net "SAS_EXP_A_PWR12")
		)
		(pad "3" smd rect
			(at -0.65024 -0.8255 180)
			(size 0.4064 1.2192)
			(layers "F.Cu" "F.Mask" "F.Paste")
			(net "GND")
		)
		(pad "4" smd rect
			(at -0.65024 0.8255 180)
			(size 0.4064 1.2192)
			(layers "F.Cu" "F.Mask" "F.Paste")
			(net "DRIVE_PWR12")
		)
		(pad "5" smd rect
			(at 0.65024 0.8255 180)
			(size 0.4064 1.2192)
			(layers "F.Cu" "F.Mask" "F.Paste")
			(net "P3V3")
		)
	)
	(footprint ""
		(layer "F.Cu")
		(at 245.9228 -423.037 -90)
		(property "Reference" "C356"
			(at 0 0 270)
			(layer "F.SilkS")
			(hide yes)
			(effects
				(font
					(size 1.27 1.27)
				)
			)
		)
		(property "Value" "SC220P50V3JN-GP"
			(at 0 -2.8194 270)
			(unlocked yes)
			(layer "F.Fab")
			(hide yes)
			(effects
				(font
					(size 1.016 1.016)
					(thickness 0.1524)
				)
			)
		)
		(property "Device Type" "C603H36"
			(at 0 -4.3434 270)
			(unlocked yes)
			(layer "F.Fab")
			(hide yes)
			(effects
				(font
					(size 1.016 1.016)
					(thickness 0.1524)
				)
			)
		)
		(duplicate_pad_numbers_are_jumpers no)
		(fp_line
			(start 0.508 0)
			(end -0.508 0)
			(stroke
				(width 0.2032)
				(type default)
			)
			(layer "F.SilkS")
		)
		(fp_rect
			(start -0.5842 1.3335)
			(end 0.5842 -1.3335)
			(stroke
				(width 0)
				(type default)
			)
			(fill no)
			(layer "F.CrtYd")
		)
		(fp_rect
			(start -0.5842 1.3335)
			(end 0.5842 -1.3335)
			(stroke
				(width 0)
				(type default)
			)
			(fill no)
			(layer "F.Fab")
		)
		(pad "1" smd custom
			(at 0 -0.762 270)
			(size 0.2159 0.2159)
			(layers "F.Cu" "F.Mask" "F.Paste")
			(net "I2C_C_SCL")
			(options
				(clearance outline)
				(anchor circle)
			)
			(primitives
				(gr_poly
					(pts
						(arc
							(start -0.3302 -0.4318)
							(mid -0.402042 -0.402042)
							(end -0.4318 -0.3302)
						)
						(arc
							(start -0.4318 0.3302)
							(mid -0.402042 0.402042)
							(end -0.3302 0.4318)
						)
						(arc
							(start 0.3302 0.4318)
							(mid 0.402042 0.402042)
							(end 0.4318 0.3302)
						)
						(arc
							(start 0.4318 -0.3302)
							(mid 0.402042 -0.402042)
							(end 0.3302 -0.4318)
						)
					)
					(width 0)
					(fill yes)
				)
			)
		)
		(pad "2" smd custom
			(at 0 0.762 270)
			(size 0.2159 0.2159)
			(layers "F.Cu" "F.Mask" "F.Paste")
			(net "GND")
			(options
				(clearance outline)
				(anchor circle)
			)
			(primitives
				(gr_poly
					(pts
						(arc
							(start -0.3302 -0.4318)
							(mid -0.402042 -0.402042)
							(end -0.4318 -0.3302)
						)
						(arc
							(start -0.4318 0.3302)
							(mid -0.402042 0.402042)
							(end -0.3302 0.4318)
						)
						(arc
							(start 0.3302 0.4318)
							(mid 0.402042 0.402042)
							(end 0.4318 0.3302)
						)
						(arc
							(start 0.4318 -0.3302)
							(mid 0.402042 -0.402042)
							(end 0.3302 -0.4318)
						)
					)
					(width 0)
					(fill yes)
				)
			)
		)
	)
	(footprint ""
		(layer "F.Cu")
		(at 192.278 -294.259 90)
		(property "Reference" "R550"
			(at 0 0 90)
			(layer "F.SilkS")
			(hide yes)
			(effects
				(font
					(size 1.27 1.27)
				)
			)
		)
		(property "Value" "200KR2F-L-GP"
			(at 0.064008 -3.993896 90)
			(unlocked yes)
			(layer "F.Fab")
			(hide yes)
			(effects
				(font
					(size 1.016 1.016)
					(thickness 0.1524)
				)
			)
		)
		(property "Device Type" "R402H16"
			(at 0.064008 -5.517896 90)
			(unlocked yes)
			(layer "F.Fab")
			(hide yes)
			(effects
				(font
					(size 1.016 1.016)
					(thickness 0.1524)
				)
			)
		)
		(duplicate_pad_numbers_are_jumpers no)
		(fp_line
			(start 0.508 -0.9398)
			(end -0.508 -0.9398)
			(stroke
				(width 0.1524)
				(type default)
			)
			(layer "F.SilkS")
		)
		(fp_line
			(start -0.508 -0.9398)
			(end -0.508 0.9398)
			(stroke
				(width 0.1524)
				(type default)
			)
			(layer "F.SilkS")
		)
		(fp_rect
			(start -0.508 0.9398)
			(end 0.508 -0.9398)
			(stroke
				(width 0)
				(type default)
			)
			(fill no)
			(layer "F.CrtYd")
		)
		(fp_rect
			(start -0.508 0.9398)
			(end 0.508 -0.9398)
			(stroke
				(width 0)
				(type default)
			)
			(fill no)
			(layer "F.Fab")
		)
		(pad "1" smd custom
			(at 0 -0.4445 90)
			(size 0.1397 0.1397)
			(layers "F.Cu" "F.Mask" "F.Paste")
			(net "SW_HDD2_R")
			(options
				(clearance outline)
				(anchor circle)
			)
			(primitives
				(gr_poly
					(pts
						(arc
							(start -0.1778 -0.2794)
							(mid -0.249642 -0.249642)
							(end -0.2794 -0.1778)
						)
						(arc
							(start -0.2794 0.1778)
							(mid -0.249642 0.249642)
							(end -0.1778 0.2794)
						)
						(arc
							(start 0.1778 0.2794)
							(mid 0.249642 0.249642)
							(end 0.2794 0.1778)
						)
						(arc
							(start 0.2794 -0.1778)
							(mid 0.249642 -0.249642)
							(end 0.1778 -0.2794)
						)
					)
					(width 0)
					(fill yes)
				)
			)
		)
		(pad "2" smd custom
			(at 0 0.4445 90)
			(size 0.1397 0.1397)
			(layers "F.Cu" "F.Mask" "F.Paste")
			(net "SW_HDD2_N")
			(options
				(clearance outline)
				(anchor circle)
			)
			(primitives
				(gr_poly
					(pts
						(arc
							(start -0.1778 -0.2794)
							(mid -0.249642 -0.249642)
							(end -0.2794 -0.1778)
						)
						(arc
							(start -0.2794 0.1778)
							(mid -0.249642 0.249642)
							(end -0.1778 0.2794)
						)
						(arc
							(start 0.1778 0.2794)
							(mid 0.249642 0.249642)
							(end 0.2794 0.1778)
						)
						(arc
							(start 0.2794 -0.1778)
							(mid 0.249642 -0.249642)
							(end 0.1778 -0.2794)
						)
					)
					(width 0)
					(fill yes)
				)
			)
		)
	)
)
